(kicad_pcb
	(version 20241229)
	(generator "pcbnew")
	(generator_version "9.0")
	(general
		(thickness 1.6642)
		(legacy_teardrops no)
	)
	(paper "A3")
	(title_block
		(title "PolarFire SoM")
		(date "2025-07-22")
		(rev "1.1.4")
		(company "Antmicro Ltd")
		(comment 1 "www.antmicro.com")
		(comment 9 "footprints 65-69 of 470")
	)
	(layers
		(0 "F.Cu" mixed)
		(4 "In1.Cu" power)
		(6 "In2.Cu" signal)
		(8 "In3.Cu" power)
		(10 "In4.Cu" signal)
		(12 "In5.Cu" power)
		(14 "In6.Cu" power)
		(16 "In7.Cu" signal)
		(18 "In8.Cu" power)
		(20 "In9.Cu" signal)
		(22 "In10.Cu" power)
		(24 "In11.Cu" signal)
		(26 "In12.Cu" signal)
		(2 "B.Cu" mixed)
		(9 "F.Adhes" user "F.Adhesive")
		(11 "B.Adhes" user "B.Adhesive")
		(13 "F.Paste" user)
		(15 "B.Paste" user)
		(5 "F.SilkS" user "F.Silkscreen")
		(7 "B.SilkS" user "B.Silkscreen")
		(1 "F.Mask" user)
		(3 "B.Mask" user)
		(17 "Dwgs.User" user "User.Drawings")
		(19 "Cmts.User" user "User.Comments")
		(21 "Eco1.User" user "User.Eco1")
		(23 "Eco2.User" user "User.Eco2")
		(25 "Edge.Cuts" user)
		(27 "Margin" user)
		(31 "F.CrtYd" user "F.Courtyard")
		(29 "B.CrtYd" user "B.Courtyard")
		(35 "F.Fab" user)
		(33 "B.Fab" user)
	)
	(footprint "antmicro-footprints:R_0402_1005Metric"
		(layer "F.Cu")
		(at 197.802486 117.687335)
		(descr "Resistor SMD 0402")
		(tags "resistor SMD 0402")
		(property "Reference" "R15"
			(at -2.362486 -0.697335 0)
			(layer "F.SilkS")
			(effects
				(font
					(size 0.7 0.7)
					(thickness 0.15)
				)
				(justify left bottom)
			)
		)
		(property "Value" "R_10k_0402"
			(at -1.011843 1.772047 0)
			(layer "F.Fab")
			(hide yes)
			(effects
				(font
					(size 0.7 0.7)
					(thickness 0.15)
				)
				(justify left bottom)
			)
		)
		(property "Datasheet" "https://www.bourns.com/docs/product-datasheets/cr.pdf"
			(at 0 0 0)
			(layer "F.Fab")
			(hide yes)
			(effects
				(font
					(size 1.27 1.27)
					(thickness 0.15)
				)
			)
		)
		(property "Description" "SMD Chip Resistor, 10 kohm, ± 1%, 62.5 mW, 0402 [1005 Metric], Thick Film, General Purpose"
			(at 0 0 0)
			(layer "F.Fab")
			(hide yes)
			(effects
				(font
					(size 1.27 1.27)
					(thickness 0.15)
				)
			)
		)
		(property "Author" "Antmicro"
			(at 0 0 0)
			(layer "F.Fab")
			(hide yes)
			(effects
				(font
					(size 1 1)
					(thickness 0.15)
				)
			)
		)
		(property "DNP" "DNP"
			(at 0 0 0)
			(layer "F.Fab")
			(hide yes)
			(effects
				(font
					(size 1 1)
					(thickness 0.15)
				)
			)
		)
		(property "License" "Apache-2.0"
			(at 0 0 0)
			(layer "F.Fab")
			(hide yes)
			(effects
				(font
					(size 1 1)
					(thickness 0.15)
				)
			)
		)
		(property "MPN" "CR0402-FX-1002GLF"
			(at 0 0 0)
			(layer "F.Fab")
			(hide yes)
			(effects
				(font
					(size 1 1)
					(thickness 0.15)
				)
			)
		)
		(property "Manufacturer" "Bourns"
			(at 0 0 0)
			(layer "F.Fab")
			(hide yes)
			(effects
				(font
					(size 1 1)
					(thickness 0.15)
				)
			)
		)
		(property "Public" ""
			(at 0 0 0)
			(layer "F.Fab")
			(hide yes)
			(effects
				(font
					(size 1 1)
					(thickness 0.15)
				)
			)
		)
		(property "Tolerance" "1%"
			(at 0 0 0)
			(layer "F.Fab")
			(hide yes)
			(effects
				(font
					(size 1 1)
					(thickness 0.15)
				)
			)
		)
		(property "Val" "10k"
			(at 0 0 0)
			(layer "F.Fab")
			(hide yes)
			(effects
				(font
					(size 1 1)
					(thickness 0.15)
				)
			)
		)
		(sheetname "/Top Connector/")
		(sheetfile "top-connector.kicad_sch")
		(attr smd dnp)
		(fp_rect
			(start -0.925 -0.47)
			(end 0.925 0.47)
			(stroke
				(width 0.05)
				(type default)
			)
			(fill no)
			(layer "F.CrtYd")
		)
		(fp_rect
			(start -0.5 -0.25)
			(end 0.5 0.25)
			(stroke
				(width 0.15)
				(type solid)
			)
			(fill no)
			(layer "F.Fab")
		)
		(fp_text user "License: Apache-2.0"
			(at -0.95 5.169 0)
			(layer "F.Fab")
			(effects
				(font
					(size 0.7 0.7)
					(thickness 0.15)
				)
				(justify left bottom)
			)
		)
		(fp_text user "Author: Antmicro"
			(at -0.95 4.169 0)
			(layer "F.Fab")
			(effects
				(font
					(size 0.7 0.7)
					(thickness 0.15)
				)
				(justify left bottom)
			)
		)
		(fp_text user "${REFERENCE}"
			(at -0.95 3.168 0)
			(layer "F.Fab")
			(effects
				(font
					(size 0.7 0.7)
					(thickness 0.15)
				)
				(justify left bottom)
			)
		)
		(pad "1" smd roundrect
			(at -0.48 0)
			(size 0.59 0.64)
			(layers "F.Cu" "F.Mask" "F.Paste")
			(roundrect_rratio 0.25)
			(net 221 "VBUS")
			(pintype "passive")
		)
		(pad "2" smd roundrect
			(at 0.48 0)
			(size 0.59 0.64)
			(layers "F.Cu" "F.Mask" "F.Paste")
			(roundrect_rratio 0.25)
			(net 245 "Net-(J1-Pad50)")
			(pintype "passive")
		)
	)
	(footprint "antmicro-footprints:D_0402_1005Metric"
		(layer "F.Cu")
		(at 210.200425 153.723639 90)
		(property "Reference" "D2"
			(at -1.546361 1.319575 90)
			(layer "F.SilkS")
			(effects
				(font
					(size 0.7 0.7)
					(thickness 0.15)
				)
				(justify left bottom)
			)
		)
		(property "Value" "AXGD10402KR"
			(at -2.54 2.54 90)
			(layer "F.Fab")
			(hide yes)
			(effects
				(font
					(size 0.7 0.7)
					(thickness 0.15)
				)
				(justify left bottom)
			)
		)
		(property "Datasheet" "https://www.littelfuse.com/media?resourcetype=datasheets&itemid=020b2bf2-064c-4ff1-a898-b4ec805b2fea&filename=littelfuse-xtremeguard-axgd-datasheet"
			(at 0 0 90)
			(layer "F.Fab")
			(hide yes)
			(effects
				(font
					(size 1.27 1.27)
					(thickness 0.15)
				)
			)
		)
		(property "Description" "Bidirectional TVS, 30 kV,  0402, 24 V, 0.04 pF"
			(at 0 0 90)
			(layer "F.Fab")
			(hide yes)
			(effects
				(font
					(size 1.27 1.27)
					(thickness 0.15)
				)
			)
		)
		(property "Author" "Antmicro"
			(at 363.924064 -56.476786 0)
			(layer "F.Fab")
			(hide yes)
			(effects
				(font
					(size 1 1)
					(thickness 0.15)
				)
			)
		)
		(property "License" "Apache-2.0"
			(at 363.924064 -56.476786 0)
			(layer "F.Fab")
			(hide yes)
			(effects
				(font
					(size 1 1)
					(thickness 0.15)
				)
			)
		)
		(property "MPN" "AXGD10402KR"
			(at 363.924064 -56.476786 0)
			(layer "F.Fab")
			(hide yes)
			(effects
				(font
					(size 1 1)
					(thickness 0.15)
				)
			)
		)
		(property "Manufacturer" "Littelfuse"
			(at 363.924064 -56.476786 0)
			(layer "F.Fab")
			(hide yes)
			(effects
				(font
					(size 1 1)
					(thickness 0.15)
				)
			)
		)
		(property "Public" ""
			(at 363.924064 -56.476786 0)
			(layer "F.Fab")
			(hide yes)
			(effects
				(font
					(size 1 1)
					(thickness 0.15)
				)
			)
		)
		(sheetname "/USB/")
		(sheetfile "usb.kicad_sch")
		(attr smd)
		(fp_line
			(start 0.1 -0.255)
			(end -0.1 -0.255)
			(stroke
				(width 0.15)
				(type solid)
			)
			(layer "F.SilkS")
		)
		(fp_line
			(start -0.875 -0.25)
			(end -0.875 0.25)
			(stroke
				(width 0.15)
				(type solid)
			)
			(layer "F.SilkS")
		)
		(fp_line
			(start -0.1 0.255)
			(end 0.1 0.255)
			(stroke
				(width 0.15)
				(type solid)
			)
			(layer "F.SilkS")
		)
		(fp_rect
			(start -0.925 -0.47)
			(end 0.925 0.47)
			(stroke
				(width 0.05)
				(type default)
			)
			(fill no)
			(layer "F.CrtYd")
		)
		(fp_line
			(start 0.51 -0.255)
			(end 0.51 0.255)
			(stroke
				(width 0.15)
				(type solid)
			)
			(layer "F.Fab")
		)
		(fp_line
			(start -0.51 -0.255)
			(end 0.51 -0.255)
			(stroke
				(width 0.15)
				(type solid)
			)
			(layer "F.Fab")
		)
		(fp_line
			(start -0.2 -0.25)
			(end -0.5 0.05)
			(stroke
				(width 0.15)
				(type solid)
			)
			(layer "F.Fab")
		)
		(fp_line
			(start 0.51 0.255)
			(end -0.51 0.255)
			(stroke
				(width 0.15)
				(type solid)
			)
			(layer "F.Fab")
		)
		(fp_line
			(start -0.51 0.255)
			(end -0.51 -0.255)
			(stroke
				(width 0.15)
				(type solid)
			)
			(layer "F.Fab")
		)
		(fp_text user "Author: Antmicro"
			(at -2.54 6.94 90)
			(layer "F.Fab")
			(effects
				(font
					(size 0.7 0.7)
					(thickness 0.15)
				)
				(justify left bottom)
			)
		)
		(fp_text user "License: Apache-2.0"
			(at -2.54 5.74 90)
			(layer "F.Fab")
			(effects
				(font
					(size 0.7 0.7)
					(thickness 0.15)
				)
				(justify left bottom)
			)
		)
		(fp_text user "${REFERENCE}"
			(at -2.54 4.54 90)
			(layer "F.Fab")
			(effects
				(font
					(size 0.7 0.7)
					(thickness 0.15)
				)
				(justify left bottom)
			)
		)
		(pad "1" smd roundrect
			(at -0.48 0 90)
			(size 0.59 0.64)
			(layers "F.Cu" "F.Mask" "F.Paste")
			(roundrect_rratio 0.25)
			(net 417 "GND")
			(pinfunction "C")
			(pintype "passive")
		)
		(pad "2" smd roundrect
			(at 0.48 0 90)
			(size 0.59 0.64)
			(layers "F.Cu" "F.Mask" "F.Paste")
			(roundrect_rratio 0.25)
			(net 15 "/Bottom Connector/CONN.D_N")
			(pinfunction "A")
			(pintype "passive")
		)
	)
	(footprint "antmicro-footprints:TP_SMD_0.75mm"
		(layer "F.Cu")
		(at 190.35 147.28)
		(property "Reference" "TP17"
			(at 0 -0.6 0)
			(layer "F.SilkS")
			(hide yes)
			(effects
				(font
					(size 0.7 0.7)
					(thickness 0.15)
				)
				(justify left bottom)
			)
		)
		(property "Value" "TP_0.75mm_SMD"
			(at 0 1.2 0)
			(layer "F.Fab")
			(hide yes)
			(effects
				(font
					(size 0.7 0.7)
					(thickness 0.15)
				)
				(justify left bottom)
			)
		)
		(property "Description" "SMT test point"
			(at 0 0 0)
			(layer "F.Fab")
			(hide yes)
			(effects
				(font
					(size 1.27 1.27)
					(thickness 0.15)
				)
			)
		)
		(property "Author" "Antmicro"
			(at 0 0 0)
			(layer "F.Fab")
			(hide yes)
			(effects
				(font
					(size 1 1)
					(thickness 0.15)
				)
			)
		)
		(property "License" "Apache-2.0"
			(at 0 0 0)
			(layer "F.Fab")
			(hide yes)
			(effects
				(font
					(size 1 1)
					(thickness 0.15)
				)
			)
		)
		(property "MPN" ""
			(at 0 0 0)
			(layer "F.Fab")
			(hide yes)
			(effects
				(font
					(size 1 1)
					(thickness 0.15)
				)
			)
		)
		(property "Manufacturer" ""
			(at 0 0 0)
			(layer "F.Fab")
			(hide yes)
			(effects
				(font
					(size 1 1)
					(thickness 0.15)
				)
			)
		)
		(property "Public" "False"
			(at 0 0 0)
			(layer "F.Fab")
			(hide yes)
			(effects
				(font
					(size 1 1)
					(thickness 0.15)
				)
			)
		)
		(sheetname "/HDMI/")
		(sheetfile "hdmi.kicad_sch")
		(attr exclude_from_pos_files exclude_from_bom)
		(fp_circle
			(center 0 0)
			(end 0.475 0)
			(stroke
				(width 0.05)
				(type default)
			)
			(fill no)
			(layer "F.CrtYd")
		)
		(fp_text user "License: Apache-2.0"
			(at -0.4 5.101 0)
			(layer "F.Fab")
			(effects
				(font
					(size 0.7 0.7)
					(thickness 0.15)
				)
				(justify left bottom)
			)
		)
		(fp_text user "Author: Antmicro"
			(at -0.4 3.901 0)
			(layer "F.Fab")
			(effects
				(font
					(size 0.7 0.7)
					(thickness 0.15)
				)
				(justify left bottom)
			)
		)
		(fp_text user "${REFERENCE}"
			(at -0.4 2.7 0)
			(layer "F.Fab")
			(effects
				(font
					(size 0.7 0.7)
					(thickness 0.15)
				)
				(justify left bottom)
			)
		)
		(pad "1" smd circle
			(at 0 0)
			(size 0.75 0.75)
			(layers "F.Cu" "F.Mask")
			(net 555 "Net-(U15-OC_S0)")
			(pinfunction "1")
			(pintype "passive")
		)
	)
	(footprint "antmicro-footprints:TP_SMD_0.75mm"
		(layer "F.Cu")
		(at 228.47 149.03 90)
		(property "Reference" "TP16"
			(at -3.68 9.76 180)
			(layer "F.SilkS")
			(hide yes)
			(effects
				(font
					(size 0.7 0.7)
					(thickness 0.15)
				)
				(justify left bottom)
			)
		)
		(property "Value" "TP_0.75mm_SMD"
			(at 0 1.2 90)
			(layer "F.Fab")
			(hide yes)
			(effects
				(font
					(size 0.7 0.7)
					(thickness 0.15)
				)
				(justify left bottom)
			)
		)
		(property "Description" "SMT test point"
			(at 0 0 90)
			(layer "F.Fab")
			(hide yes)
			(effects
				(font
					(size 1.27 1.27)
					(thickness 0.15)
				)
			)
		)
		(property "Author" "Antmicro"
			(at 377.5 -79.44 0)
			(layer "F.Fab")
			(hide yes)
			(effects
				(font
					(size 1 1)
					(thickness 0.15)
				)
			)
		)
		(property "License" "Apache-2.0"
			(at 377.5 -79.44 0)
			(layer "F.Fab")
			(hide yes)
			(effects
				(font
					(size 1 1)
					(thickness 0.15)
				)
			)
		)
		(property "MPN" ""
			(at 377.5 -79.44 0)
			(layer "F.Fab")
			(hide yes)
			(effects
				(font
					(size 1 1)
					(thickness 0.15)
				)
			)
		)
		(property "Manufacturer" ""
			(at 377.5 -79.44 0)
			(layer "F.Fab")
			(hide yes)
			(effects
				(font
					(size 1 1)
					(thickness 0.15)
				)
			)
		)
		(property "Public" "False"
			(at 377.5 -79.44 0)
			(layer "F.Fab")
			(hide yes)
			(effects
				(font
					(size 1 1)
					(thickness 0.15)
				)
			)
		)
		(sheetname "/WiFi_Bluetooth/")
		(sheetfile "wifi_bt.kicad_sch")
		(attr exclude_from_pos_files exclude_from_bom)
		(fp_circle
			(center 0 0)
			(end 0.475 0)
			(stroke
				(width 0.05)
				(type default)
			)
			(fill no)
			(layer "F.CrtYd")
		)
		(fp_text user "Author: Antmicro"
			(at -0.4 3.901 90)
			(layer "F.Fab")
			(effects
				(font
					(size 0.7 0.7)
					(thickness 0.15)
				)
				(justify left bottom)
			)
		)
		(fp_text user "${REFERENCE}"
			(at -0.4 2.7 90)
			(layer "F.Fab")
			(effects
				(font
					(size 0.7 0.7)
					(thickness 0.15)
				)
				(justify left bottom)
			)
		)
		(fp_text user "License: Apache-2.0"
			(at -0.4 5.101 90)
			(layer "F.Fab")
			(effects
				(font
					(size 0.7 0.7)
					(thickness 0.15)
				)
				(justify left bottom)
			)
		)
		(pad "1" smd circle
			(at 0 0 90)
			(size 0.75 0.75)
			(layers "F.Cu" "F.Mask")
			(net 521 "Net-(U26A-BT_PCM_OUT)")
			(pinfunction "1")
			(pintype "passive")
		)
	)
	(footprint "antmicro-footprints:Fiducial_1mm_Mask2mm"
		(layer "F.Cu")
		(at 175.76 120.865)
		(descr "Circular Fiducial, 1mm bare copper, 3mm soldermask opening")
		(tags "fiducial")
		(property "Reference" "FD1"
			(at 0 -1.4 0)
			(layer "F.SilkS")
			(hide yes)
			(effects
				(font
					(size 0.7 0.7)
					(thickness 0.15)
				)
				(justify left bottom)
			)
		)
		(property "Value" "Fiducial_1mm_Mask2mm"
			(at 0 2.2 0)
			(layer "F.Fab")
			(hide yes)
			(effects
				(font
					(size 0.7 0.7)
					(thickness 0.15)
				)
				(justify left bottom)
			)
		)
		(property "Description" "Fiducial mask "
			(at 0 0 0)
			(layer "F.Fab")
			(hide yes)
			(effects
				(font
					(size 1.27 1.27)
					(thickness 0.15)
				)
			)
		)
		(property "Author" "Antmicro"
			(at 0 0 0)
			(layer "F.Fab")
			(hide yes)
			(effects
				(font
					(size 1 1)
					(thickness 0.15)
				)
			)
		)
		(property "License" "Apache-2.0"
			(at 0 0 0)
			(layer "F.Fab")
			(hide yes)
			(effects
				(font
					(size 1 1)
					(thickness 0.15)
				)
			)
		)
		(property "exclude_from_bom" ""
			(at 0 0 0)
			(layer "F.Fab")
			(hide yes)
			(effects
				(font
					(size 1 1)
					(thickness 0.15)
				)
			)
		)
		(sheetfile "polarfire-som.kicad_sch")
		(attr board_only exclude_from_pos_files exclude_from_bom)
		(fp_circle
			(center 0 0)
			(end 1.24 0)
			(stroke
				(width 0.05)
				(type solid)
			)
			(fill no)
			(layer "F.CrtYd")
		)
		(fp_circle
			(center 0 0)
			(end 0.999 0)
			(stroke
				(width 0.15)
				(type solid)
			)
			(fill no)
			(layer "F.Fab")
		)
		(fp_text user "License: Apache-2.0"
			(at -1.25 7.003 0)
			(layer "F.Fab")
			(effects
				(font
					(size 0.7 0.7)
					(thickness 0.15)
				)
				(justify left bottom)
			)
		)
		(fp_text user "Author: Antmicro"
			(at -1.25 5.803 0)
			(layer "F.Fab")
			(effects
				(font
					(size 0.7 0.7)
					(thickness 0.15)
				)
				(justify left bottom)
			)
		)
		(fp_text user "${REFERENCE}"
			(at -1.25 4.603 0)
			(layer "F.Fab")
			(effects
				(font
					(size 0.7 0.7)
					(thickness 0.15)
				)
				(justify left bottom)
			)
		)
		(pad "" smd circle
			(at 0 0)
			(size 1 1)
			(layers "F.Cu" "F.Mask")
			(solder_mask_margin 0.5)
			(clearance 0.5)
		)
	)
)
